(kicad_pcb
	(version 20260206)
	(generator "pcbnew")
	(generator_version "10.0")
	(general
		(thickness 1.6)
		(legacy_teardrops no)
	)
	(paper "A4")
	(title_block
		(title "timecard-production-celestica-r4006 — R4006-B0001-02_R01.brd")
		(comment 1 "Time Appliance Project (Time Card) / footprints 986-989 of 1113")
	)
	(layers
		(0 "F.Cu" signal "TOP")
		(4 "In1.Cu" signal "L02_GND1")
		(6 "In2.Cu" signal "L03_SIG1")
		(8 "In3.Cu" signal "L04_GND2")
		(10 "In4.Cu" signal "L05_VCC1")
		(12 "In5.Cu" signal "L06_VCC2")
		(14 "In6.Cu" signal "L07_GND3")
		(16 "In7.Cu" signal "L08_SIG2")
		(18 "In8.Cu" signal "L09_GND4")
		(2 "B.Cu" signal "BOTTOM")
		(9 "F.Adhes" user "F.Adhesive")
		(11 "B.Adhes" user "B.Adhesive")
		(13 "F.Paste" user "Package Geometry/Pastemask Top")
		(15 "B.Paste" user "Package Geometry/Pastemask Bottom")
		(5 "F.SilkS" user "Ref Des/Silkscreen Top")
		(7 "B.SilkS" user "Ref Des/Silkscreen Bottom")
		(1 "F.Mask" user "Board Geometry/Soldermask Top")
		(3 "B.Mask" user "Board Geometry/Soldermask Bottom")
		(17 "Dwgs.User" user "User.Drawings")
		(19 "Cmts.User" user "User.Comments")
		(21 "Eco1.User" user "User.Eco1")
		(23 "Eco2.User" user "User.Eco2")
		(25 "Edge.Cuts" user "Board Geometry/Outline")
		(27 "Margin" user)
		(31 "F.CrtYd" user "Package Geometry/Place Bound Top")
		(29 "B.CrtYd" user "Package Geometry/Place Bound Bottom")
		(35 "F.Fab" user "Ref Des/Assembly Top")
		(33 "B.Fab" user "Ref Des/Assembly Bottom")
	)
	(footprint ""
		(layer "B.Cu")
		(at 76.581 -58.801 -90)
		(property "Reference" "Q3"
			(at -2.413 -5.16763 270)
			(unlocked yes)
			(layer "B.SilkS")
			(effects
				(font
					(size 0.7874 0.5842)
					(thickness 0.1524)
				)
				(justify mirror)
			)
		)
		(property "Value" ""
			(at 0 0 90)
			(layer "B.Fab")
			(effects
				(font
					(size 1.27 1.27)
				)
				(justify mirror)
			)
		)
		(property "User Part Number" "PARTNUM*"
			(at -5.207254 -0.501904 270)
			(unlocked yes)
			(layer "Cmts.User")
			(hide yes)
			(effects
				(font
					(size 0.7874 0.5842)
					(thickness 0.000001)
				)
				(justify mirror)
			)
		)
		(property "Device Type" "POWERMOS_3P_PCH-G121-10216-01"
			(at -3.642614 -1.544828 270)
			(unlocked yes)
			(layer "B.Fab")
			(hide yes)
			(effects
				(font
					(size 0.7874 0.5842)
					(thickness 0.000001)
				)
				(justify mirror)
			)
		)
		(duplicate_pad_numbers_are_jumpers no)
		(fp_line
			(start -1.7018 2.0574)
			(end -0.1905 2.0574)
			(stroke
				(width 0.1)
				(type default)
			)
			(layer "B.SilkS")
		)
		(fp_line
			(start -0.1905 2.0574)
			(end -0.1905 0.9144)
			(stroke
				(width 0.1)
				(type default)
			)
			(layer "B.SilkS")
		)
		(fp_line
			(start 0.1905 2.0574)
			(end 1.7018 2.0574)
			(stroke
				(width 0.1)
				(type default)
			)
			(layer "B.SilkS")
		)
		(fp_line
			(start 1.7018 2.0574)
			(end 1.7018 -0.9144)
			(stroke
				(width 0.1)
				(type default)
			)
			(layer "B.SilkS")
		)
		(fp_line
			(start -0.1905 0.9144)
			(end 0.1905 0.9144)
			(stroke
				(width 0.1)
				(type default)
			)
			(layer "B.SilkS")
		)
		(fp_line
			(start 0.1905 0.9144)
			(end 0.1905 2.0574)
			(stroke
				(width 0.1)
				(type default)
			)
			(layer "B.SilkS")
		)
		(fp_line
			(start -1.7018 -0.9144)
			(end -1.7018 2.0574)
			(stroke
				(width 0.1)
				(type default)
			)
			(layer "B.SilkS")
		)
		(fp_line
			(start -0.7493 -0.9144)
			(end -1.7018 -0.9144)
			(stroke
				(width 0.1)
				(type default)
			)
			(layer "B.SilkS")
		)
		(fp_line
			(start 0.7493 -0.9144)
			(end 0.7493 -2.0574)
			(stroke
				(width 0.1)
				(type default)
			)
			(layer "B.SilkS")
		)
		(fp_line
			(start 1.7018 -0.9144)
			(end 0.7493 -0.9144)
			(stroke
				(width 0.1)
				(type default)
			)
			(layer "B.SilkS")
		)
		(fp_line
			(start -0.7493 -2.0574)
			(end -0.7493 -0.9144)
			(stroke
				(width 0.1)
				(type default)
			)
			(layer "B.SilkS")
		)
		(fp_line
			(start 0.7493 -2.0574)
			(end -0.7493 -2.0574)
			(stroke
				(width 0.1)
				(type default)
			)
			(layer "B.SilkS")
		)
		(fp_poly
			(pts
				(arc
					(start 1.524 2.413)
					(mid 1.524 3.175)
					(end 1.524 2.413)
				)
			)
			(stroke
				(width 0)
				(type default)
			)
			(fill yes)
			(layer "B.SilkS")
		)
		(fp_poly
			(pts
				(xy 1.7018 2.0828) (xy 1.7018 -0.9144) (xy 0.762 -0.9144) (xy 0.762 -2.0574) (xy -0.762 -2.0574)
				(xy -0.762 -0.9144) (xy -1.7018 -0.9144) (xy -1.7018 2.0828)
			)
			(stroke
				(width 0)
				(type default)
			)
			(fill no)
			(layer "B.CrtYd")
		)
		(fp_line
			(start -1.1684 1.143)
			(end -0.7112 1.143)
			(stroke
				(width 0.1)
				(type default)
			)
			(layer "B.Fab")
		)
		(fp_line
			(start -0.7112 1.143)
			(end -0.7112 0.6604)
			(stroke
				(width 0.1)
				(type default)
			)
			(layer "B.Fab")
		)
		(fp_line
			(start 0.7112 1.143)
			(end 1.1684 1.143)
			(stroke
				(width 0.1)
				(type default)
			)
			(layer "B.Fab")
		)
		(fp_line
			(start 1.1684 1.143)
			(end 1.1684 0.6604)
			(stroke
				(width 0.1)
				(type default)
			)
			(layer "B.Fab")
		)
		(fp_line
			(start -0.7112 0.9144)
			(end -1.1684 0.9144)
			(stroke
				(width 0.1)
				(type default)
			)
			(layer "B.Fab")
		)
		(fp_line
			(start 1.1684 0.9144)
			(end 0.7112 0.9144)
			(stroke
				(width 0.1)
				(type default)
			)
			(layer "B.Fab")
		)
		(fp_line
			(start -1.4478 0.6604)
			(end 1.4478 0.6604)
			(stroke
				(width 0.1)
				(type default)
			)
			(layer "B.Fab")
		)
		(fp_line
			(start -1.1684 0.6604)
			(end -1.1684 1.143)
			(stroke
				(width 0.1)
				(type default)
			)
			(layer "B.Fab")
		)
		(fp_line
			(start -0.7112 0.6604)
			(end -1.1684 0.6604)
			(stroke
				(width 0.1)
				(type default)
			)
			(layer "B.Fab")
		)
		(fp_line
			(start 0.7112 0.6604)
			(end 0.7112 1.143)
			(stroke
				(width 0.1)
				(type default)
			)
			(layer "B.Fab")
		)
		(fp_line
			(start 1.1684 0.6604)
			(end 0.7112 0.6604)
			(stroke
				(width 0.1)
				(type default)
			)
			(layer "B.Fab")
		)
		(fp_line
			(start 1.4478 0.6604)
			(end 1.3716 0.5842)
			(stroke
				(width 0.1)
				(type default)
			)
			(layer "B.Fab")
		)
		(fp_line
			(start 1.4478 0.6604)
			(end 1.4478 -0.6604)
			(stroke
				(width 0.1)
				(type default)
			)
			(layer "B.Fab")
		)
		(fp_line
			(start -1.3716 0.5842)
			(end -1.4478 0.6604)
			(stroke
				(width 0.1)
				(type default)
			)
			(layer "B.Fab")
		)
		(fp_line
			(start -1.3716 0.5842)
			(end 1.3716 0.5842)
			(stroke
				(width 0.1)
				(type default)
			)
			(layer "B.Fab")
		)
		(fp_line
			(start 1.3716 0.5842)
			(end 1.3716 -0.5842)
			(stroke
				(width 0.1)
				(type default)
			)
			(layer "B.Fab")
		)
		(fp_line
			(start -1.3716 -0.5842)
			(end -1.3716 0.5842)
			(stroke
				(width 0.1)
				(type default)
			)
			(layer "B.Fab")
		)
		(fp_line
			(start -1.3716 -0.5842)
			(end -1.4478 -0.6604)
			(stroke
				(width 0.1)
				(type default)
			)
			(layer "B.Fab")
		)
		(fp_line
			(start 1.3716 -0.5842)
			(end -1.3716 -0.5842)
			(stroke
				(width 0.1)
				(type default)
			)
			(layer "B.Fab")
		)
		(fp_line
			(start -1.4478 -0.6604)
			(end -1.4478 0.6604)
			(stroke
				(width 0.1)
				(type default)
			)
			(layer "B.Fab")
		)
		(fp_line
			(start -0.2286 -0.6604)
			(end 0.2286 -0.6604)
			(stroke
				(width 0.1)
				(type default)
			)
			(layer "B.Fab")
		)
		(fp_line
			(start 0.2286 -0.6604)
			(end 0.2286 -1.143)
			(stroke
				(width 0.1)
				(type default)
			)
			(layer "B.Fab")
		)
		(fp_line
			(start 1.4478 -0.6604)
			(end 1.3716 -0.5842)
			(stroke
				(width 0.1)
				(type default)
			)
			(layer "B.Fab")
		)
		(fp_line
			(start 1.4478 -0.6604)
			(end -1.4478 -0.6604)
			(stroke
				(width 0.1)
				(type default)
			)
			(layer "B.Fab")
		)
		(fp_line
			(start 0.2286 -0.9144)
			(end -0.2286 -0.9144)
			(stroke
				(width 0.1)
				(type default)
			)
			(layer "B.Fab")
		)
		(fp_line
			(start -0.2286 -1.143)
			(end -0.2286 -0.6604)
			(stroke
				(width 0.1)
				(type default)
			)
			(layer "B.Fab")
		)
		(fp_line
			(start 0.2286 -1.143)
			(end -0.2286 -1.143)
			(stroke
				(width 0.1)
				(type default)
			)
			(layer "B.Fab")
		)
		(fp_poly
			(pts
				(arc
					(start 1.651 1.27)
					(mid 1.651 2.032)
					(end 1.651 1.27)
				)
			)
			(stroke
				(width 0)
				(type default)
			)
			(fill yes)
			(layer "B.Fab")
		)
		(fp_text user "2"
			(at -1.8288 1.30175 270)
			(unlocked yes)
			(layer "B.SilkS")
			(effects
				(font
					(size 0.635 0.4064)
					(thickness 0.1524)
				)
				(justify left mirror)
			)
		)
		(fp_text user "2"
			(at -1.23063 1.4859 0)
			(unlocked yes)
			(layer "B.Fab")
			(effects
				(font
					(size 0.7874 0.5842)
					(thickness 0.1524)
				)
				(justify left mirror)
			)
		)
		(pad "1" smd rect
			(at 0.9398 1.1049 90)
			(size 0.9906 1.397)
			(layers "B.Cu" "B.Mask" "B.Paste")
			(net "UNNAMED_527_POWERMOS3PNCHV1_I23")
		)
		(pad "2" smd rect
			(at -0.9398 1.1049 90)
			(size 0.9906 1.397)
			(layers "B.Cu" "B.Mask" "B.Paste")
			(net "XP5R0V_MAC")
		)
		(pad "3" smd rect
			(at 0 -1.1049 90)
			(size 0.9906 1.397)
			(layers "B.Cu" "B.Mask" "B.Paste")
			(net "UNNAMED_527_FUSE_I244_1")
		)
	)
	(footprint ""
		(layer "B.Cu")
		(at 107.696 -100.6348 -90)
		(property "Reference" "C316"
			(at 2.2098 1.05537 270)
			(unlocked yes)
			(layer "B.SilkS")
			(effects
				(font
					(size 0.7874 0.5842)
					(thickness 0.1524)
				)
				(justify mirror)
			)
		)
		(property "Value" "VAL*"
			(at -0.0762 2.067306 270)
			(unlocked yes)
			(layer "B.Fab")
			(hide yes)
			(effects
				(font
					(size 0.7874 0.5842)
					(thickness 0.1524)
				)
				(justify mirror)
			)
		)
		(property "Tolerance" "TOL*"
			(at -0.0762 3.032506 270)
			(unlocked yes)
			(layer "Cmts.User")
			(hide yes)
			(effects
				(font
					(size 0.7874 0.5842)
					(thickness 0.1524)
				)
				(justify mirror)
			)
		)
		(property "User Part Number" "PARTNUM*"
			(at -0.1016 4.023106 270)
			(unlocked yes)
			(layer "Cmts.User")
			(hide yes)
			(effects
				(font
					(size 0.7874 0.5842)
					(thickness 0.1524)
				)
				(justify mirror)
			)
		)
		(property "Device Type" "CAPACITOR-G105-0B104-EK,0.1UF,A"
			(at -0.0508 1.127506 270)
			(unlocked yes)
			(layer "B.Fab")
			(hide yes)
			(effects
				(font
					(size 0.7874 0.5842)
					(thickness 0.1524)
				)
				(justify mirror)
			)
		)
		(duplicate_pad_numbers_are_jumpers no)
		(fp_line
			(start -1.143 0.5588)
			(end -1.143 -0.5588)
			(stroke
				(width 0.1)
				(type default)
			)
			(layer "B.SilkS")
		)
		(fp_line
			(start 1.143 0.5588)
			(end -1.143 0.5588)
			(stroke
				(width 0.1)
				(type default)
			)
			(layer "B.SilkS")
		)
		(fp_line
			(start -1.143 -0.5588)
			(end 1.143 -0.5588)
			(stroke
				(width 0.1)
				(type default)
			)
			(layer "B.SilkS")
		)
		(fp_line
			(start 1.143 -0.5588)
			(end 1.143 0.5588)
			(stroke
				(width 0.1)
				(type default)
			)
			(layer "B.SilkS")
		)
		(fp_poly
			(pts
				(xy 1.143 0.5588) (xy -1.143 0.5588) (xy -1.143 -0.5588) (xy 1.143 -0.5588)
			)
			(stroke
				(width 0)
				(type default)
			)
			(fill no)
			(layer "B.CrtYd")
		)
		(fp_line
			(start -0.508 0.3048)
			(end -0.508 -0.3048)
			(stroke
				(width 0.1)
				(type default)
			)
			(layer "B.Fab")
		)
		(fp_line
			(start 0.508 0.3048)
			(end -0.508 0.3048)
			(stroke
				(width 0.1)
				(type default)
			)
			(layer "B.Fab")
		)
		(fp_line
			(start -0.508 -0.3048)
			(end 0.508 -0.3048)
			(stroke
				(width 0.1)
				(type default)
			)
			(layer "B.Fab")
		)
		(fp_line
			(start 0.508 -0.3048)
			(end 0.508 0.3048)
			(stroke
				(width 0.1)
				(type default)
			)
			(layer "B.Fab")
		)
		(pad "1" smd rect
			(at 0.5334 0 90)
			(size 0.7112 0.6096)
			(layers "B.Cu" "B.Mask" "B.Paste")
			(net "RGB_LED_SHUTDOWN_N")
		)
		(pad "2" smd rect
			(at -0.5334 0 90)
			(size 0.7112 0.6096)
			(layers "B.Cu" "B.Mask" "B.Paste")
			(net "SG")
		)
		(zone
			(layer "B.Cu")
			(hatch none 0.5)
			(connect_pads
				(clearance 0)
			)
			(min_thickness 0.25)
			(keepout
				(tracks not_allowed)
				(vias allowed)
				(pads allowed)
				(copperpour not_allowed)
				(footprints allowed)
			)
			(placement
				(enabled no)
				(sheetname "")
			)
			(fill
				(thermal_gap 0.5)
				(thermal_bridge_width 0.5)
				(island_removal_mode 0)
			)
			(polygon
				(pts
					(xy 107.3912 -100.5586) (xy 108.0008 -100.5586) (xy 108.0008 -100.711) (xy 107.3912 -100.711)
				)
			)
		)
		(zone
			(layer "B.Cu")
			(hatch none 0.5)
			(connect_pads
				(clearance 0)
			)
			(min_thickness 0.25)
			(keepout
				(tracks allowed)
				(vias not_allowed)
				(pads allowed)
				(copperpour not_allowed)
				(footprints allowed)
			)
			(placement
				(enabled no)
				(sheetname "")
			)
			(fill
				(thermal_gap 0.5)
				(thermal_bridge_width 0.5)
				(island_removal_mode 0)
			)
			(polygon
				(pts
					(xy 107.3912 -100.5586) (xy 108.0008 -100.5586) (xy 108.0008 -100.711) (xy 107.3912 -100.711)
				)
			)
		)
	)
	(footprint ""
		(layer "B.Cu")
		(at 106.847132 -36.323016 -90)
		(property "Reference" "C208"
			(at 1.525016 41.600882 270)
			(unlocked yes)
			(layer "B.SilkS")
			(effects
				(font
					(size 0.635 0.4064)
					(thickness 0.1524)
				)
				(justify mirror)
			)
		)
		(property "Value" "VAL*"
			(at 0 3.718306 270)
			(unlocked yes)
			(layer "B.Fab")
			(hide yes)
			(effects
				(font
					(size 0.7874 0.5842)
					(thickness 0.127)
				)
				(justify mirror)
			)
		)
		(property "Device Type" "CAPACITOR-G105-0B104-CK,0.1UF,A"
			(at 0 1.432306 270)
			(unlocked yes)
			(layer "B.Fab")
			(hide yes)
			(effects
				(font
					(size 0.7874 0.5842)
					(thickness 0.127)
				)
				(justify mirror)
			)
		)
		(property "User Part Number" "PARTNUM*"
			(at 0 2.575306 270)
			(unlocked yes)
			(layer "Cmts.User")
			(hide yes)
			(effects
				(font
					(size 0.7874 0.5842)
					(thickness 0.127)
				)
				(justify mirror)
			)
		)
		(property "Tolerance" "TOL*"
			(at 0 4.861306 270)
			(unlocked yes)
			(layer "Cmts.User")
			(hide yes)
			(effects
				(font
					(size 0.7874 0.5842)
					(thickness 0.127)
				)
				(justify mirror)
			)
		)
		(duplicate_pad_numbers_are_jumpers no)
		(fp_line
			(start -0.970026 0.4699)
			(end 0.970026 0.4699)
			(stroke
				(width 0.1)
				(type default)
			)
			(layer "B.SilkS")
		)
		(fp_line
			(start 0.970026 0.4699)
			(end 0.970026 -0.4699)
			(stroke
				(width 0.1)
				(type default)
			)
			(layer "B.SilkS")
		)
		(fp_line
			(start -0.970026 -0.4699)
			(end -0.970026 0.4699)
			(stroke
				(width 0.1)
				(type default)
			)
			(layer "B.SilkS")
		)
		(fp_line
			(start 0.970026 -0.4699)
			(end -0.970026 -0.4699)
			(stroke
				(width 0.1)
				(type default)
			)
			(layer "B.SilkS")
		)
		(fp_poly
			(pts
				(xy 0.970026 0.4699) (xy -0.970026 0.4699) (xy -0.970026 -0.4699) (xy 0.970026 -0.4699)
			)
			(stroke
				(width 0)
				(type default)
			)
			(fill no)
			(layer "B.CrtYd")
		)
		(fp_line
			(start -0.508 0.3048)
			(end 0.508 0.3048)
			(stroke
				(width 0.1)
				(type default)
			)
			(layer "B.Fab")
		)
		(fp_line
			(start 0.508 0.3048)
			(end 0.508 -0.3048)
			(stroke
				(width 0.1)
				(type default)
			)
			(layer "B.Fab")
		)
		(fp_line
			(start -0.508 -0.3048)
			(end -0.508 0.3048)
			(stroke
				(width 0.1)
				(type default)
			)
			(layer "B.Fab")
		)
		(fp_line
			(start 0.508 -0.3048)
			(end -0.508 -0.3048)
			(stroke
				(width 0.1)
				(type default)
			)
			(layer "B.Fab")
		)
		(pad "1" smd circle
			(at 0.500126 0 90)
			(size 0.635 0.635)
			(layers "B.Cu" "B.Mask" "B.Paste")
			(net "XP2R5V_FPGA")
		)
		(pad "2" smd circle
			(at -0.500126 0 90)
			(size 0.635 0.635)
			(layers "B.Cu" "B.Mask" "B.Paste")
			(net "SG")
		)
	)
	(footprint ""
		(layer "B.Cu")
		(at 30.34792 -16.73098 180)
		(property "Reference" "R1991"
			(at 0.75692 -1.27635 0)
			(unlocked yes)
			(layer "B.SilkS")
			(effects
				(font
					(size 0.7874 0.5842)
					(thickness 0.1524)
				)
				(justify mirror)
			)
		)
		(property "Value" "VAL*"
			(at -0.02032 2.13233 180)
			(unlocked yes)
			(layer "B.Fab")
			(hide yes)
			(effects
				(font
					(size 0.7874 0.5842)
					(thickness 0.1524)
				)
				(justify mirror)
			)
		)
		(property "Tolerance" "TOL*"
			(at -0.044704 3.05435 180)
			(unlocked yes)
			(layer "Cmts.User")
			(hide yes)
			(effects
				(font
					(size 0.7874 0.5842)
					(thickness 0.1524)
				)
				(justify mirror)
			)
		)
		(property "User Part Number" "PARTNUM*"
			(at -0.02032 4.024884 180)
			(unlocked yes)
			(layer "Cmts.User")
			(hide yes)
			(effects
				(font
					(size 0.7874 0.5842)
					(thickness 0.1524)
				)
				(justify mirror)
			)
		)
		(property "Device Type" "RESISTOR-G155-11002-01,10KOHM,A"
			(at -0.008382 1.210564 180)
			(unlocked yes)
			(layer "B.Fab")
			(hide yes)
			(effects
				(font
					(size 0.7874 0.5842)
					(thickness 0.1524)
				)
				(justify mirror)
			)
		)
		(duplicate_pad_numbers_are_jumpers no)
		(fp_line
			(start 1.143 0.5588)
			(end -1.143 0.5588)
			(stroke
				(width 0.1)
				(type default)
			)
			(layer "B.SilkS")
		)
		(fp_line
			(start 1.143 -0.5588)
			(end 1.143 0.5588)
			(stroke
				(width 0.1)
				(type default)
			)
			(layer "B.SilkS")
		)
		(fp_line
			(start -1.143 0.5588)
			(end -1.143 -0.5588)
			(stroke
				(width 0.1)
				(type default)
			)
			(layer "B.SilkS")
		)
		(fp_line
			(start -1.143 -0.5588)
			(end 1.143 -0.5588)
			(stroke
				(width 0.1)
				(type default)
			)
			(layer "B.SilkS")
		)
		(fp_rect
			(start 1.143 -0.5588)
			(end -1.143 0.5588)
			(stroke
				(width 0)
				(type default)
			)
			(fill no)
			(layer "B.CrtYd")
		)
		(fp_line
			(start 0.508 0.3048)
			(end -0.508 0.3048)
			(stroke
				(width 0.1)
				(type default)
			)
			(layer "B.Fab")
		)
		(fp_line
			(start 0.508 -0.3048)
			(end 0.508 0.3048)
			(stroke
				(width 0.1)
				(type default)
			)
			(layer "B.Fab")
		)
		(fp_line
			(start -0.508 0.3048)
			(end -0.508 -0.3048)
			(stroke
				(width 0.1)
				(type default)
			)
			(layer "B.Fab")
		)
		(fp_line
			(start -0.508 -0.3048)
			(end 0.508 -0.3048)
			(stroke
				(width 0.1)
				(type default)
			)
			(layer "B.Fab")
		)
		(pad "1" smd rect
			(at 0.5334 0)
			(size 0.7112 0.6096)
			(layers "B.Cu" "B.Mask" "B.Paste")
			(net "XP3R3V_FPGA")
		)
		(pad "2" smd rect
			(at -0.5334 0)
			(size 0.7112 0.6096)
			(layers "B.Cu" "B.Mask" "B.Paste")
			(net "EEPROM_SDA")
		)
		(zone
			(layer "B.Cu")
			(hatch none 0.5)
			(connect_pads
				(clearance 0)
			)
			(min_thickness 0.25)
			(keepout
				(tracks allowed)
				(vias not_allowed)
				(pads allowed)
				(copperpour not_allowed)
				(footprints allowed)
			)
			(placement
				(enabled no)
				(sheetname "")
			)
			(fill
				(thermal_gap 0.5)
				(thermal_bridge_width 0.5)
				(island_removal_mode 0)
			)
			(polygon
				(pts
					(xy 30.27172 -16.42618) (xy 30.42412 -16.42618) (xy 30.42412 -17.03578) (xy 30.27172 -17.03578)
				)
			)
		)
	)
)
